(kicad_pcb
	(version 20260206)
	(generator "pcbnew")
	(generator_version "10.0")
	(general
		(thickness 1.6)
		(legacy_teardrops no)
	)
	(paper "A4")
	(title_block
		(title "Wiwynn_Tioga_Pass_MB.brd")
		(comment 1 "Tioga Pass / footprints 4686-4693 of 4770")
	)
	(layers
		(0 "F.Cu" signal "TOP")
		(4 "In1.Cu" signal "L2GND")
		(6 "In2.Cu" signal "L3")
		(8 "In3.Cu" signal "L4GND")
		(10 "In4.Cu" signal "L5")
		(12 "In5.Cu" signal "L6GND")
		(14 "In6.Cu" signal "L7VCC")
		(16 "In7.Cu" signal "L8VCC")
		(18 "In8.Cu" signal "L9GND")
		(20 "In9.Cu" signal "L10")
		(22 "In10.Cu" signal "L11GND")
		(24 "In11.Cu" signal "L12")
		(26 "In12.Cu" signal "L13GND")
		(2 "B.Cu" signal "BOTTOM")
		(9 "F.Adhes" user "F.Adhesive")
		(11 "B.Adhes" user "B.Adhesive")
		(13 "F.Paste" user "Package Geometry/Pastemask Top")
		(15 "B.Paste" user "Package Geometry/Pastemask Bottom")
		(5 "F.SilkS" user "Ref Des/Silkscreen Top")
		(7 "B.SilkS" user "Ref Des/Silkscreen Bottom")
		(1 "F.Mask" user "Board Geometry/Soldermask Top")
		(3 "B.Mask" user "Board Geometry/Soldermask Bottom")
		(17 "Dwgs.User" user "User.Drawings")
		(19 "Cmts.User" user "User.Comments")
		(21 "Eco1.User" user "User.Eco1")
		(23 "Eco2.User" user "User.Eco2")
		(25 "Edge.Cuts" user "Board Geometry/Outline")
		(27 "Margin" user)
		(31 "F.CrtYd" user "Package Geometry/Place Bound Top")
		(29 "B.CrtYd" user "Package Geometry/Place Bound Bottom")
		(35 "F.Fab" user "Ref Des/Assembly Top")
		(33 "B.Fab" user "Ref Des/Assembly Bottom")
	)
	(footprint ""
		(layer "B.Cu")
		(at 355.736398 -77.915516 180)
		(property "Reference" "C3P35"
			(at 0 0 0)
			(layer "B.SilkS")
			(hide yes)
			(effects
				(font
					(size 1.27 1.27)
				)
				(justify mirror)
			)
		)
		(property "Value" ""
			(at 0 0 0)
			(layer "B.Fab")
			(effects
				(font
					(size 1.27 1.27)
				)
				(justify mirror)
			)
		)
		(duplicate_pad_numbers_are_jumpers no)
		(fp_poly
			(pts
				(xy -0.3048 -0.1016) (xy -0.3048 0.9906) (xy 0.3048 0.9906) (xy 0.3048 -0.1016)
			)
			(stroke
				(width 0)
				(type default)
			)
			(fill no)
			(layer "B.CrtYd")
		)
		(fp_line
			(start 0.3048 0.9906)
			(end -0.3048 0.9906)
			(stroke
				(width 0.1)
				(type default)
			)
			(layer "B.Fab")
		)
		(fp_line
			(start 0.3048 -0.1016)
			(end 0.3048 0.9906)
			(stroke
				(width 0.1)
				(type default)
			)
			(layer "B.Fab")
		)
		(fp_line
			(start -0.3048 0.9906)
			(end -0.3048 -0.1016)
			(stroke
				(width 0.1)
				(type default)
			)
			(layer "B.Fab")
		)
		(fp_line
			(start -0.3048 -0.1016)
			(end 0.3048 -0.1016)
			(stroke
				(width 0.1)
				(type default)
			)
			(layer "B.Fab")
		)
		(pad "1" smd rect
			(at 0 0)
			(size 0.508 0.508)
			(layers "B.Cu" "B.Mask" "B.Paste")
			(net "P3E_CPU0_PE1_SS_TXP<6>")
		)
		(pad "2" smd rect
			(at 0 0.889)
			(size 0.508 0.508)
			(layers "B.Cu" "B.Mask" "B.Paste")
			(net "P3E_CPU0_PE1_PCH_TXP<6>")
		)
		(zone
			(layer "B.Cu")
			(hatch none 0.5)
			(connect_pads
				(clearance 0)
			)
			(min_thickness 0.25)
			(keepout
				(tracks not_allowed)
				(vias allowed)
				(pads allowed)
				(copperpour not_allowed)
				(footprints allowed)
			)
			(placement
				(enabled no)
				(sheetname "")
			)
			(fill
				(thermal_gap 0.5)
				(thermal_bridge_width 0.5)
				(island_removal_mode 0)
			)
			(polygon
				(pts
					(xy 355.482398 -78.550516) (xy 355.990398 -78.550516) (xy 355.990398 -78.169516) (xy 355.482398 -78.169516)
				)
			)
		)
		(zone
			(layer "B.Cu")
			(hatch none 0.5)
			(connect_pads
				(clearance 0)
			)
			(min_thickness 0.25)
			(keepout
				(tracks allowed)
				(vias not_allowed)
				(pads allowed)
				(copperpour not_allowed)
				(footprints allowed)
			)
			(placement
				(enabled no)
				(sheetname "")
			)
			(fill
				(thermal_gap 0.5)
				(thermal_bridge_width 0.5)
				(island_removal_mode 0)
			)
			(polygon
				(pts
					(xy 355.482398 -78.169516) (xy 355.990398 -78.169516) (xy 355.990398 -78.550516) (xy 355.482398 -78.550516)
				)
			)
		)
	)
	(footprint ""
		(layer "B.Cu")
		(at 336.140806 -60.368434)
		(property "Reference" "R2U16"
			(at 0 0 0)
			(layer "B.SilkS")
			(hide yes)
			(effects
				(font
					(size 1.27 1.27)
				)
				(justify mirror)
			)
		)
		(property "Value" ""
			(at 0 0 0)
			(layer "B.Fab")
			(effects
				(font
					(size 1.27 1.27)
				)
				(justify mirror)
			)
		)
		(duplicate_pad_numbers_are_jumpers no)
		(fp_poly
			(pts
				(xy 0.2794 -0.1016) (xy -0.2794 -0.1016) (xy -0.2794 0.9906) (xy 0.2794 0.9906)
			)
			(stroke
				(width 0)
				(type default)
			)
			(fill no)
			(layer "B.CrtYd")
		)
		(fp_line
			(start -0.2794 -0.1016)
			(end 0.2794 -0.1016)
			(stroke
				(width 0.1)
				(type default)
			)
			(layer "B.Fab")
		)
		(fp_line
			(start -0.2794 0.9906)
			(end -0.2794 -0.1016)
			(stroke
				(width 0.1)
				(type default)
			)
			(layer "B.Fab")
		)
		(fp_line
			(start 0.2794 -0.1016)
			(end 0.2794 0.9906)
			(stroke
				(width 0.1)
				(type default)
			)
			(layer "B.Fab")
		)
		(fp_line
			(start 0.2794 0.9906)
			(end -0.2794 0.9906)
			(stroke
				(width 0.1)
				(type default)
			)
			(layer "B.Fab")
		)
		(pad "1" smd rect
			(at 0 0 180)
			(size 0.508 0.508)
			(layers "B.Cu" "B.Mask" "B.Paste")
			(net "P3E_CPU0_PE1_SS_RXP<1>")
		)
		(pad "2" smd rect
			(at 0 0.889 180)
			(size 0.508 0.508)
			(layers "B.Cu" "B.Mask" "B.Paste")
			(net "P3E_CPU0_PE1_SS_R_RXP<1>")
		)
		(zone
			(layer "B.Cu")
			(hatch none 0.5)
			(connect_pads
				(clearance 0)
			)
			(min_thickness 0.25)
			(keepout
				(tracks allowed)
				(vias not_allowed)
				(pads allowed)
				(copperpour not_allowed)
				(footprints allowed)
			)
			(placement
				(enabled no)
				(sheetname "")
			)
			(fill
				(thermal_gap 0.5)
				(thermal_bridge_width 0.5)
				(island_removal_mode 0)
			)
			(polygon
				(pts
					(xy 336.394806 -60.114434) (xy 335.886806 -60.114434) (xy 335.886806 -59.733434) (xy 336.394806 -59.733434)
				)
			)
		)
		(zone
			(layer "B.Cu")
			(hatch none 0.5)
			(connect_pads
				(clearance 0)
			)
			(min_thickness 0.25)
			(keepout
				(tracks not_allowed)
				(vias allowed)
				(pads allowed)
				(copperpour not_allowed)
				(footprints allowed)
			)
			(placement
				(enabled no)
				(sheetname "")
			)
			(fill
				(thermal_gap 0.5)
				(thermal_bridge_width 0.5)
				(island_removal_mode 0)
			)
			(polygon
				(pts
					(xy 336.394806 -59.733434) (xy 335.886806 -59.733434) (xy 335.886806 -60.114434) (xy 336.394806 -60.114434)
				)
			)
		)
	)
	(footprint ""
		(layer "B.Cu")
		(at 10.551668 -3.321812 180)
		(property "Reference" "R9U3"
			(at 0 0 0)
			(layer "B.SilkS")
			(hide yes)
			(effects
				(font
					(size 1.27 1.27)
				)
				(justify mirror)
			)
		)
		(property "Value" ""
			(at 0 0 0)
			(layer "B.Fab")
			(effects
				(font
					(size 1.27 1.27)
				)
				(justify mirror)
			)
		)
		(duplicate_pad_numbers_are_jumpers no)
		(fp_rect
			(start 0.2794 0.9906)
			(end -0.2794 -0.1016)
			(stroke
				(width 0)
				(type default)
			)
			(fill no)
			(layer "B.CrtYd")
		)
		(fp_line
			(start 0.2794 0.9906)
			(end -0.2794 0.9906)
			(stroke
				(width 0.1)
				(type default)
			)
			(layer "B.Fab")
		)
		(fp_line
			(start 0.2794 -0.1016)
			(end 0.2794 0.9906)
			(stroke
				(width 0.1)
				(type default)
			)
			(layer "B.Fab")
		)
		(fp_line
			(start -0.2794 0.9906)
			(end -0.2794 -0.1016)
			(stroke
				(width 0.1)
				(type default)
			)
			(layer "B.Fab")
		)
		(fp_line
			(start -0.2794 -0.1016)
			(end 0.2794 -0.1016)
			(stroke
				(width 0.1)
				(type default)
			)
			(layer "B.Fab")
		)
		(pad "1" smd rect
			(at 0 0)
			(size 0.508 0.508)
			(layers "B.Cu" "B.Mask" "B.Paste")
			(net "PVCCIO_CPU1")
		)
		(pad "2" smd rect
			(at 0 0.889)
			(size 0.508 0.508)
			(layers "B.Cu" "B.Mask" "B.Paste")
			(net "SVID_DIO1_CPU1_R")
		)
		(zone
			(layer "B.Cu")
			(hatch none 0.5)
			(connect_pads
				(clearance 0)
			)
			(min_thickness 0.25)
			(keepout
				(tracks allowed)
				(vias not_allowed)
				(pads allowed)
				(copperpour not_allowed)
				(footprints allowed)
			)
			(placement
				(enabled no)
				(sheetname "")
			)
			(fill
				(thermal_gap 0.5)
				(thermal_bridge_width 0.5)
				(island_removal_mode 0)
			)
			(polygon
				(pts
					(xy 10.297668 -3.956812) (xy 10.297668 -3.575812) (xy 10.805668 -3.575812) (xy 10.805668 -3.956812)
				)
			)
		)
		(zone
			(layer "B.Cu")
			(hatch none 0.5)
			(connect_pads
				(clearance 0)
			)
			(min_thickness 0.25)
			(keepout
				(tracks not_allowed)
				(vias allowed)
				(pads allowed)
				(copperpour not_allowed)
				(footprints allowed)
			)
			(placement
				(enabled no)
				(sheetname "")
			)
			(fill
				(thermal_gap 0.5)
				(thermal_bridge_width 0.5)
				(island_removal_mode 0)
			)
			(polygon
				(pts
					(xy 10.297668 -3.956812) (xy 10.297668 -3.575812) (xy 10.805668 -3.575812) (xy 10.805668 -3.956812)
				)
			)
		)
	)
	(footprint ""
		(layer "B.Cu")
		(at 402.4503 -37.8968 -90)
		(property "Reference" "R2U10"
			(at 0 0 90)
			(layer "B.SilkS")
			(hide yes)
			(effects
				(font
					(size 1.27 1.27)
				)
				(justify mirror)
			)
		)
		(property "Value" ""
			(at 0 0 90)
			(layer "B.Fab")
			(effects
				(font
					(size 1.27 1.27)
				)
				(justify mirror)
			)
		)
		(duplicate_pad_numbers_are_jumpers no)
		(fp_poly
			(pts
				(xy 0.2794 -0.1016) (xy -0.2794 -0.1016) (xy -0.2794 0.9906) (xy 0.2794 0.9906)
			)
			(stroke
				(width 0)
				(type default)
			)
			(fill no)
			(layer "B.CrtYd")
		)
		(fp_line
			(start -0.2794 0.9906)
			(end -0.2794 -0.1016)
			(stroke
				(width 0.1)
				(type default)
			)
			(layer "B.Fab")
		)
		(fp_line
			(start 0.2794 0.9906)
			(end -0.2794 0.9906)
			(stroke
				(width 0.1)
				(type default)
			)
			(layer "B.Fab")
		)
		(fp_line
			(start -0.2794 -0.1016)
			(end 0.2794 -0.1016)
			(stroke
				(width 0.1)
				(type default)
			)
			(layer "B.Fab")
		)
		(fp_line
			(start 0.2794 -0.1016)
			(end 0.2794 0.9906)
			(stroke
				(width 0.1)
				(type default)
			)
			(layer "B.Fab")
		)
		(pad "1" smd rect
			(at 0 0 90)
			(size 0.508 0.508)
			(layers "B.Cu" "B.Mask" "B.Paste")
			(net "SMB_OCP_FRU_STBY_LVC3_SDA_R")
		)
		(pad "2" smd rect
			(at 0 0.889 90)
			(size 0.508 0.508)
			(layers "B.Cu" "B.Mask" "B.Paste")
			(net "SMB_OCP_FRU_STBY_LVC3_SDA")
		)
		(zone
			(layer "B.Cu")
			(hatch none 0.5)
			(connect_pads
				(clearance 0)
			)
			(min_thickness 0.25)
			(keepout
				(tracks not_allowed)
				(vias allowed)
				(pads allowed)
				(copperpour not_allowed)
				(footprints allowed)
			)
			(placement
				(enabled no)
				(sheetname "")
			)
			(fill
				(thermal_gap 0.5)
				(thermal_bridge_width 0.5)
				(island_removal_mode 0)
			)
			(polygon
				(pts
					(xy 401.8153 -37.6428) (xy 401.8153 -38.1508) (xy 402.1963 -38.1508) (xy 402.1963 -37.6428)
				)
			)
		)
		(zone
			(layer "B.Cu")
			(hatch none 0.5)
			(connect_pads
				(clearance 0)
			)
			(min_thickness 0.25)
			(keepout
				(tracks allowed)
				(vias not_allowed)
				(pads allowed)
				(copperpour not_allowed)
				(footprints allowed)
			)
			(placement
				(enabled no)
				(sheetname "")
			)
			(fill
				(thermal_gap 0.5)
				(thermal_bridge_width 0.5)
				(island_removal_mode 0)
			)
			(polygon
				(pts
					(xy 402.1963 -37.6428) (xy 402.1963 -38.1508) (xy 401.8153 -38.1508) (xy 401.8153 -37.6428)
				)
			)
		)
	)
	(footprint ""
		(layer "B.Cu")
		(at 344.59037 -133.92277 180)
		(property "Reference" "C22W7"
			(at 0 0 0)
			(layer "B.SilkS")
			(hide yes)
			(effects
				(font
					(size 1.27 1.27)
				)
				(justify mirror)
			)
		)
		(property "Value" "*"
			(at 0.0762 -6.2357 180)
			(unlocked yes)
			(layer "B.Fab")
			(hide yes)
			(effects
				(font
					(size 1.27 1.016)
					(thickness 0.1524)
				)
				(justify mirror)
			)
		)
		(property "Device Type" "SC22U16V5MX-4-GP_SMD-BCG5-SC22A"
			(at 0.0762 -8.2677 180)
			(unlocked yes)
			(layer "B.Fab")
			(hide yes)
			(effects
				(font
					(size 1.27 1.016)
					(thickness 0.1524)
				)
				(justify mirror)
			)
		)
		(duplicate_pad_numbers_are_jumpers no)
		(fp_line
			(start -0.635 0)
			(end 0.635 0)
			(stroke
				(width 0.508)
				(type default)
			)
			(layer "B.SilkS")
		)
		(fp_rect
			(start 0.9652 1.778)
			(end -0.9652 -1.778)
			(stroke
				(width 0)
				(type default)
			)
			(fill no)
			(layer "B.CrtYd")
		)
		(fp_poly
			(pts
				(xy 0.9652 -1.778) (xy -0.9652 -1.778) (xy -0.9652 1.778) (xy 0.9652 1.778)
			)
			(stroke
				(width 0)
				(type default)
			)
			(fill no)
			(layer "B.Fab")
		)
		(pad "1" smd rect
			(at 0 -0.9652)
			(size 1.397 1.143)
			(layers "B.Cu" "B.Mask" "B.Paste")
			(net "VR_FET_SW_P12V_STBY_PVPP_DEF")
		)
		(pad "2" smd rect
			(at 0 0.9652)
			(size 1.397 1.143)
			(layers "B.Cu" "B.Mask" "B.Paste")
			(net "GND")
		)
	)
	(footprint ""
		(layer "B.Cu")
		(at 380.8476 -137.541)
		(property "Reference" "C3L27"
			(at 0 0 0)
			(layer "B.SilkS")
			(hide yes)
			(effects
				(font
					(size 1.27 1.27)
				)
				(justify mirror)
			)
		)
		(property "Value" ""
			(at 0 0 0)
			(layer "B.Fab")
			(effects
				(font
					(size 1.27 1.27)
				)
				(justify mirror)
			)
		)
		(duplicate_pad_numbers_are_jumpers no)
		(fp_poly
			(pts
				(xy 0.4953 -0.2032) (xy -0.4953 -0.2032) (xy -0.4953 1.6002) (xy 0.4953 1.6002)
			)
			(stroke
				(width 0)
				(type default)
			)
			(fill no)
			(layer "B.CrtYd")
		)
		(fp_line
			(start -0.4953 -0.2032)
			(end -0.4953 1.6002)
			(stroke
				(width 0.1)
				(type default)
			)
			(layer "B.Fab")
		)
		(fp_line
			(start -0.4953 1.6002)
			(end 0.4953 1.6002)
			(stroke
				(width 0.1)
				(type default)
			)
			(layer "B.Fab")
		)
		(fp_line
			(start 0.4953 -0.2032)
			(end -0.4953 -0.2032)
			(stroke
				(width 0.1)
				(type default)
			)
			(layer "B.Fab")
		)
		(fp_line
			(start 0.4953 1.6002)
			(end 0.4953 -0.2032)
			(stroke
				(width 0.1)
				(type default)
			)
			(layer "B.Fab")
		)
		(pad "1" smd rect
			(at 0 0 180)
			(size 0.762 0.889)
			(layers "B.Cu" "B.Mask" "B.Paste")
			(net "PVNN_PCH_STBY")
		)
		(pad "2" smd rect
			(at 0 1.397 180)
			(size 0.762 0.889)
			(layers "B.Cu" "B.Mask" "B.Paste")
			(net "GND")
		)
		(zone
			(layer "B.Cu")
			(hatch none 0.5)
			(connect_pads
				(clearance 0)
			)
			(min_thickness 0.25)
			(keepout
				(tracks not_allowed)
				(vias allowed)
				(pads allowed)
				(copperpour not_allowed)
				(footprints allowed)
			)
			(placement
				(enabled no)
				(sheetname "")
			)
			(fill
				(thermal_gap 0.5)
				(thermal_bridge_width 0.5)
				(island_removal_mode 0)
			)
			(polygon
				(pts
					(xy 381.2286 -137.0965) (xy 380.4666 -137.0965) (xy 380.4666 -136.5885) (xy 381.2286 -136.5885)
				)
			)
		)
	)
	(footprint ""
		(layer "B.Cu")
		(at 49.4284 -63.080392)
		(property "Reference" "C9R2"
			(at 0 0 0)
			(layer "B.SilkS")
			(hide yes)
			(effects
				(font
					(size 1.27 1.27)
				)
				(justify mirror)
			)
		)
		(property "Value" ""
			(at 0 0 0)
			(layer "B.Fab")
			(effects
				(font
					(size 1.27 1.27)
				)
				(justify mirror)
			)
		)
		(duplicate_pad_numbers_are_jumpers no)
		(fp_poly
			(pts
				(xy 0.4953 -0.2032) (xy -0.4953 -0.2032) (xy -0.4953 1.6002) (xy 0.4953 1.6002)
			)
			(stroke
				(width 0)
				(type default)
			)
			(fill no)
			(layer "B.CrtYd")
		)
		(fp_line
			(start -0.4953 -0.2032)
			(end -0.4953 1.6002)
			(stroke
				(width 0.1)
				(type default)
			)
			(layer "B.Fab")
		)
		(fp_line
			(start -0.4953 1.6002)
			(end 0.4953 1.6002)
			(stroke
				(width 0.1)
				(type default)
			)
			(layer "B.Fab")
		)
		(fp_line
			(start 0.4953 -0.2032)
			(end -0.4953 -0.2032)
			(stroke
				(width 0.1)
				(type default)
			)
			(layer "B.Fab")
		)
		(fp_line
			(start 0.4953 1.6002)
			(end 0.4953 -0.2032)
			(stroke
				(width 0.1)
				(type default)
			)
			(layer "B.Fab")
		)
		(pad "1" smd rect
			(at 0 0 180)
			(size 0.762 0.889)
			(layers "B.Cu" "B.Mask" "B.Paste")
			(net "PVCCIN_CPU1")
		)
		(pad "2" smd rect
			(at 0 1.397 180)
			(size 0.762 0.889)
			(layers "B.Cu" "B.Mask" "B.Paste")
			(net "GND")
		)
		(zone
			(layer "B.Cu")
			(hatch none 0.5)
			(connect_pads
				(clearance 0)
			)
			(min_thickness 0.25)
			(keepout
				(tracks not_allowed)
				(vias allowed)
				(pads allowed)
				(copperpour not_allowed)
				(footprints allowed)
			)
			(placement
				(enabled no)
				(sheetname "")
			)
			(fill
				(thermal_gap 0.5)
				(thermal_bridge_width 0.5)
				(island_removal_mode 0)
			)
			(polygon
				(pts
					(xy 49.8094 -62.635892) (xy 49.0474 -62.635892) (xy 49.0474 -62.127892) (xy 49.8094 -62.127892)
				)
			)
		)
	)
	(footprint ""
		(layer "B.Cu")
		(at 167.616124 -23.562564 -90)
		(property "Reference" "R6T2"
			(at 0 0 90)
			(layer "B.SilkS")
			(hide yes)
			(effects
				(font
					(size 1.27 1.27)
				)
				(justify mirror)
			)
		)
		(property "Value" ""
			(at 0 0 90)
			(layer "B.Fab")
			(effects
				(font
					(size 1.27 1.27)
				)
				(justify mirror)
			)
		)
		(duplicate_pad_numbers_are_jumpers no)
		(fp_poly
			(pts
				(xy 0.2794 -0.1016) (xy -0.2794 -0.1016) (xy -0.2794 0.9906) (xy 0.2794 0.9906)
			)
			(stroke
				(width 0)
				(type default)
			)
			(fill no)
			(layer "B.CrtYd")
		)
		(fp_line
			(start -0.2794 0.9906)
			(end -0.2794 -0.1016)
			(stroke
				(width 0.1)
				(type default)
			)
			(layer "B.Fab")
		)
		(fp_line
			(start 0.2794 0.9906)
			(end -0.2794 0.9906)
			(stroke
				(width 0.1)
				(type default)
			)
			(layer "B.Fab")
		)
		(fp_line
			(start -0.2794 -0.1016)
			(end 0.2794 -0.1016)
			(stroke
				(width 0.1)
				(type default)
			)
			(layer "B.Fab")
		)
		(fp_line
			(start 0.2794 -0.1016)
			(end 0.2794 0.9906)
			(stroke
				(width 0.1)
				(type default)
			)
			(layer "B.Fab")
		)
		(pad "1" smd rect
			(at 0 0 90)
			(size 0.508 0.508)
			(layers "B.Cu" "B.Mask" "B.Paste")
			(net "PVCCIO_CPU1")
		)
		(pad "2" smd rect
			(at 0 0.889 90)
			(size 0.508 0.508)
			(layers "B.Cu" "B.Mask" "B.Paste")
			(net "SMB_DDR_GHJ_SCL_G")
		)
		(zone
			(layer "B.Cu")
			(hatch none 0.5)
			(connect_pads
				(clearance 0)
			)
			(min_thickness 0.25)
			(keepout
				(tracks not_allowed)
				(vias allowed)
				(pads allowed)
				(copperpour not_allowed)
				(footprints allowed)
			)
			(placement
				(enabled no)
				(sheetname "")
			)
			(fill
				(thermal_gap 0.5)
				(thermal_bridge_width 0.5)
				(island_removal_mode 0)
			)
			(polygon
				(pts
					(xy 166.981124 -23.308564) (xy 166.981124 -23.816564) (xy 167.362124 -23.816564) (xy 167.362124 -23.308564)
				)
			)
		)
		(zone
			(layer "B.Cu")
			(hatch none 0.5)
			(connect_pads
				(clearance 0)
			)
			(min_thickness 0.25)
			(keepout
				(tracks allowed)
				(vias not_allowed)
				(pads allowed)
				(copperpour not_allowed)
				(footprints allowed)
			)
			(placement
				(enabled no)
				(sheetname "")
			)
			(fill
				(thermal_gap 0.5)
				(thermal_bridge_width 0.5)
				(island_removal_mode 0)
			)
			(polygon
				(pts
					(xy 167.362124 -23.308564) (xy 167.362124 -23.816564) (xy 166.981124 -23.816564) (xy 166.981124 -23.308564)
				)
			)
		)
	)
)
